(kicad_pcb
	(version 20241229)
	(generator "pcbnew")
	(generator_version "9.0")
	(general
		(thickness 1.63)
		(legacy_teardrops no)
	)
	(paper "A4")
	(title_block
		(title "CM4 Baseboard")
		(date "2026-01-05")
		(rev "1.1.1")
		(company "Antmicro Ltd")
		(comment 1 "www.antmicro.com")
		(comment 9 "footprints 98-102 of 506")
	)
	(layers
		(0 "F.Cu" signal)
		(4 "In1.Cu" power)
		(6 "In2.Cu" power)
		(8 "In3.Cu" signal)
		(10 "In4.Cu" signal)
		(2 "B.Cu" signal)
		(9 "F.Adhes" user "F.Adhesive")
		(11 "B.Adhes" user "B.Adhesive")
		(13 "F.Paste" user)
		(15 "B.Paste" user)
		(5 "F.SilkS" user "F.Silkscreen")
		(7 "B.SilkS" user "B.Silkscreen")
		(1 "F.Mask" user)
		(3 "B.Mask" user)
		(17 "Dwgs.User" user "User.Drawings")
		(19 "Cmts.User" user "User.Comments")
		(21 "Eco1.User" user "User.Eco1")
		(23 "Eco2.User" user "User.Eco2")
		(25 "Edge.Cuts" user)
		(27 "Margin" user)
		(31 "F.CrtYd" user "F.Courtyard")
		(29 "B.CrtYd" user "B.Courtyard")
		(35 "F.Fab" user)
		(33 "B.Fab" user)
	)
	(footprint "antmicro-footprints:SOT-523"
		(layer "F.Cu")
		(at 101.917962 149.6165 -90)
		(property "Reference" "Q201"
			(at 1.775 -1.407038 180)
			(layer "F.SilkS")
			(effects
				(font
					(size 0.7 0.7)
					(thickness 0.15)
				)
				(justify right bottom)
			)
		)
		(property "Value" "PJE138K"
			(at 0.1 1.824 90)
			(layer "F.Fab")
			(effects
				(font
					(size 0.7 0.7)
					(thickness 0.15)
				)
				(justify right bottom)
			)
		)
		(property "Datasheet" "https://www.mouser.com/datasheet/2/1057/PJE138K-1876698.pdf"
			(at 0 0 270)
			(layer "F.Fab")
			(hide yes)
			(effects
				(font
					(size 1.27 1.27)
					(thickness 0.15)
				)
			)
		)
		(property "MPN" "PJE138K_R1_00001"
			(at 0 0 270)
			(unlocked yes)
			(layer "F.Fab")
			(hide yes)
			(effects
				(font
					(size 1 1)
					(thickness 0.15)
				)
			)
		)
		(property "Manufacturer" "PANJIT"
			(at 0 0 270)
			(unlocked yes)
			(layer "F.Fab")
			(hide yes)
			(effects
				(font
					(size 1 1)
					(thickness 0.15)
				)
			)
		)
		(property "Author" "Antmicro"
			(at 0 0 270)
			(unlocked yes)
			(layer "F.Fab")
			(hide yes)
			(effects
				(font
					(size 1 1)
					(thickness 0.15)
				)
			)
		)
		(property "License" "Apache-2.0"
			(at 0 0 270)
			(unlocked yes)
			(layer "F.Fab")
			(hide yes)
			(effects
				(font
					(size 1 1)
					(thickness 0.15)
				)
			)
		)
		(sheetname "/Compute module/")
		(sheetfile "compute-module.kicad_sch")
		(attr smd)
		(fp_line
			(start -0.927 -0.051)
			(end -0.927 -0.351)
			(stroke
				(width 0.15)
				(type solid)
			)
			(layer "F.SilkS")
		)
		(fp_line
			(start -0.927 -0.351)
			(end -0.725 -0.551)
			(stroke
				(width 0.15)
				(type solid)
			)
			(layer "F.SilkS")
		)
		(fp_line
			(start -0.725 -0.551)
			(end -0.277 -0.551)
			(stroke
				(width 0.15)
				(type solid)
			)
			(layer "F.SilkS")
		)
		(fp_line
			(start -0.277 -0.551)
			(end -0.277 -0.75)
			(stroke
				(width 0.15)
				(type solid)
			)
			(layer "F.SilkS")
		)
		(fp_circle
			(center -0.9652 0.9652)
			(end -0.9152 0.9652)
			(stroke
				(width 0.15)
				(type solid)
			)
			(fill yes)
			(layer "F.SilkS")
		)
		(fp_line
			(start -1.12 1.15)
			(end 1.1 1.15)
			(stroke
				(width 0.05)
				(type solid)
			)
			(layer "F.CrtYd")
		)
		(fp_line
			(start -1.12 -1.16)
			(end -1.12 1.15)
			(stroke
				(width 0.05)
				(type solid)
			)
			(layer "F.CrtYd")
		)
		(fp_line
			(start -1.12 -1.16)
			(end 1.1 -1.16)
			(stroke
				(width 0.05)
				(type solid)
			)
			(layer "F.CrtYd")
		)
		(fp_line
			(start 1.1 -1.16)
			(end 1.1 1.15)
			(stroke
				(width 0.05)
				(type solid)
			)
			(layer "F.CrtYd")
		)
		(fp_line
			(start 0.8 0.424)
			(end -0.802 0.424)
			(stroke
				(width 0.15)
				(type solid)
			)
			(layer "F.Fab")
		)
		(fp_line
			(start -0.802 -0.276)
			(end -0.802 0.424)
			(stroke
				(width 0.15)
				(type solid)
			)
			(layer "F.Fab")
		)
		(fp_line
			(start -0.652 -0.425)
			(end -0.802 -0.276)
			(stroke
				(width 0.15)
				(type solid)
			)
			(layer "F.Fab")
		)
		(fp_line
			(start 0.8 -0.425)
			(end 0.8 0.424)
			(stroke
				(width 0.15)
				(type solid)
			)
			(layer "F.Fab")
		)
		(fp_line
			(start 0.8 -0.425)
			(end -0.652 -0.425)
			(stroke
				(width 0.15)
				(type solid)
			)
			(layer "F.Fab")
		)
		(fp_circle
			(center -0.9652 0.9652)
			(end -0.9144 0.9652)
			(stroke
				(width 0.15)
				(type solid)
			)
			(fill no)
			(layer "F.Fab")
		)
		(fp_text user "Author: Antmicro"
			(at -1.12 6.224 270)
			(layer "F.Fab")
			(effects
				(font
					(size 0.7 0.7)
					(thickness 0.15)
				)
				(justify left bottom)
			)
		)
		(fp_text user "${REFERENCE}"
			(at -1.12 3.824 270)
			(layer "F.Fab")
			(effects
				(font
					(size 0.7 0.7)
					(thickness 0.15)
				)
				(justify left bottom)
			)
		)
		(fp_text user "License: Apache-2.0"
			(at -1.12 5.024 270)
			(layer "F.Fab")
			(effects
				(font
					(size 0.7 0.7)
					(thickness 0.15)
				)
				(justify left bottom)
			)
		)
		(pad "1" smd rect
			(at -0.5 0.65 270)
			(size 0.4 0.51)
			(layers "F.Cu" "F.Mask" "F.Paste")
			(net 231 "/Compute module/PolarfireID")
			(pinfunction "G")
			(pintype "input")
		)
		(pad "2" smd rect
			(at 0.498 0.65 270)
			(size 0.4 0.51)
			(layers "F.Cu" "F.Mask" "F.Paste")
			(net 3 "GND")
			(pinfunction "S")
			(pintype "passive")
		)
		(pad "3" smd rect
			(at 0 -0.652 270)
			(size 0.4 0.51)
			(layers "F.Cu" "F.Mask" "F.Paste")
			(net 327 "Net-(Q201-D)")
			(pinfunction "D")
			(pintype "passive")
		)
	)
	(footprint "antmicro-footprints:R_0402_1005Metric"
		(layer "F.Cu")
		(at 83.187962 162.4815 180)
		(descr "Resistor SMD 0402")
		(tags "resistor SMD 0402")
		(property "Reference" "R202"
			(at -3.83 -0.475 0)
			(layer "F.SilkS")
			(effects
				(font
					(size 0.7 0.7)
					(thickness 0.15)
				)
				(justify right bottom)
			)
		)
		(property "Value" "R_0R_0402"
			(at -1.011843 1.772047 0)
			(layer "F.Fab")
			(effects
				(font
					(size 0.7 0.7)
					(thickness 0.15)
				)
				(justify right bottom)
			)
		)
		(property "Datasheet" "https://industrial.panasonic.com/cdbs/www-data/pdf/RDA0000/AOA0000C301.pdf"
			(at 0 0 180)
			(layer "F.Fab")
			(hide yes)
			(effects
				(font
					(size 1.27 1.27)
					(thickness 0.15)
				)
			)
		)
		(property "Manufacturer" "Panasonic"
			(at 0 0 180)
			(unlocked yes)
			(layer "F.Fab")
			(hide yes)
			(effects
				(font
					(size 1 1)
					(thickness 0.15)
				)
			)
		)
		(property "MPN" "ERJ2GE0R00X"
			(at 0 0 180)
			(unlocked yes)
			(layer "F.Fab")
			(hide yes)
			(effects
				(font
					(size 1 1)
					(thickness 0.15)
				)
			)
		)
		(property "Val" "0R"
			(at 0 0 180)
			(unlocked yes)
			(layer "F.Fab")
			(hide yes)
			(effects
				(font
					(size 1 1)
					(thickness 0.15)
				)
			)
		)
		(property "License" "Apache-2.0"
			(at 0 0 180)
			(unlocked yes)
			(layer "F.Fab")
			(hide yes)
			(effects
				(font
					(size 1 1)
					(thickness 0.15)
				)
			)
		)
		(property "Author" "Antmicro"
			(at 0 0 180)
			(unlocked yes)
			(layer "F.Fab")
			(hide yes)
			(effects
				(font
					(size 1 1)
					(thickness 0.15)
				)
			)
		)
		(property "Tolerance" "~"
			(at 0 0 180)
			(unlocked yes)
			(layer "F.Fab")
			(hide yes)
			(effects
				(font
					(size 1 1)
					(thickness 0.15)
				)
			)
		)
		(property "Current" "1A"
			(at 0 0 180)
			(unlocked yes)
			(layer "F.Fab")
			(hide yes)
			(effects
				(font
					(size 1 1)
					(thickness 0.15)
				)
			)
		)
		(sheetname "/Compute module/")
		(sheetfile "compute-module.kicad_sch")
		(attr smd exclude_from_pos_files exclude_from_bom dnp)
		(fp_rect
			(start -0.925 -0.47)
			(end 0.925 0.47)
			(stroke
				(width 0.05)
				(type default)
			)
			(fill no)
			(layer "F.CrtYd")
		)
		(fp_rect
			(start -0.5 -0.25)
			(end 0.5 0.25)
			(stroke
				(width 0.15)
				(type solid)
			)
			(fill no)
			(layer "F.Fab")
		)
		(fp_text user "License: Apache-2.0"
			(at -0.95 5.169 180)
			(layer "F.Fab")
			(effects
				(font
					(size 0.7 0.7)
					(thickness 0.15)
				)
				(justify left bottom)
			)
		)
		(fp_text user "${REFERENCE}"
			(at -0.95 3.168 180)
			(layer "F.Fab")
			(effects
				(font
					(size 0.7 0.7)
					(thickness 0.15)
				)
				(justify left bottom)
			)
		)
		(fp_text user "Author: Antmicro"
			(at -0.95 4.169 180)
			(layer "F.Fab")
			(effects
				(font
					(size 0.7 0.7)
					(thickness 0.15)
				)
				(justify left bottom)
			)
		)
		(pad "1" smd roundrect
			(at -0.48 0 180)
			(size 0.59 0.64)
			(layers "F.Cu" "F.Mask" "F.Paste")
			(roundrect_rratio 0.25)
			(net 18 "V_{IO}")
			(pintype "passive")
		)
		(pad "2" smd roundrect
			(at 0.48 0 180)
			(size 0.59 0.64)
			(layers "F.Cu" "F.Mask" "F.Paste")
			(roundrect_rratio 0.25)
			(net 22 "+1V8")
			(pintype "passive")
		)
	)
	(footprint "antmicro-footprints:XDFN-2_1x0.60mm"
		(layer "F.Cu")
		(at 139.016962 164.4165 180)
		(property "Reference" "D504"
			(at 1.749 -2.56 0)
			(layer "F.SilkS")
			(effects
				(font
					(size 0.7 0.7)
					(thickness 0.15)
				)
				(justify left bottom)
			)
		)
		(property "Value" "TPD1E0B04_XDFN-2"
			(at 0 1.5 0)
			(layer "F.Fab")
			(effects
				(font
					(size 0.7 0.7)
					(thickness 0.15)
				)
				(justify right bottom)
			)
		)
		(property "Datasheet" "https://www.ti.com/general/docs/suppproductinfo.tsp?distId=26&gotoUrl=https://www.ti.com/lit/gpn/tpd1e0b04"
			(at 0 0 180)
			(layer "F.Fab")
			(hide yes)
			(effects
				(font
					(size 1.27 1.27)
					(thickness 0.15)
				)
			)
		)
		(property "MPN" "TPD1E0B04DPYR"
			(at 278.033924 328.833 0)
			(layer "F.Fab")
			(hide yes)
			(effects
				(font
					(size 1 1)
					(thickness 0.15)
				)
			)
		)
		(property "Manufacturer" "Texas Instruments"
			(at 278.033924 328.833 0)
			(layer "F.Fab")
			(hide yes)
			(effects
				(font
					(size 1 1)
					(thickness 0.15)
				)
			)
		)
		(property "Author" "Antmicro"
			(at 0 0 180)
			(unlocked yes)
			(layer "F.Fab")
			(hide yes)
			(effects
				(font
					(size 1 1)
					(thickness 0.15)
				)
			)
		)
		(property "License" "Apache-2.0"
			(at 0 0 180)
			(unlocked yes)
			(layer "F.Fab")
			(hide yes)
			(effects
				(font
					(size 1 1)
					(thickness 0.15)
				)
			)
		)
		(sheetname "/NVMe & microSD/")
		(sheetfile "nvme-micro-sd.kicad_sch")
		(attr smd)
		(fp_rect
			(start -0.725 -0.475)
			(end 0.725 0.475)
			(stroke
				(width 0.05)
				(type solid)
			)
			(fill no)
			(layer "F.CrtYd")
		)
		(fp_rect
			(start -0.55 -0.35)
			(end 0.55 0.35)
			(stroke
				(width 0.15)
				(type solid)
			)
			(fill no)
			(layer "F.Fab")
		)
		(fp_text user "Author: Antmicro"
			(at -0.8 4.4 180)
			(layer "F.Fab")
			(effects
				(font
					(size 0.7 0.7)
					(thickness 0.15)
				)
				(justify left bottom)
			)
		)
		(fp_text user "${REFERENCE}"
			(at -0.8 3.2 180)
			(layer "F.Fab")
			(effects
				(font
					(size 0.7 0.7)
					(thickness 0.15)
				)
				(justify left bottom)
			)
		)
		(fp_text user "License: Apache-2.0"
			(at -0.8 5.6 180)
			(layer "F.Fab")
			(effects
				(font
					(size 0.7 0.7)
					(thickness 0.15)
				)
				(justify left bottom)
			)
		)
		(pad "1" smd roundrect
			(at -0.351 0 180)
			(size 0.3 0.5)
			(layers "F.Cu" "F.Mask" "F.Paste")
			(roundrect_rratio 0.25)
			(net 3 "GND")
			(pinfunction "C")
			(pintype "passive")
		)
		(pad "2" smd roundrect
			(at 0.349 0 180)
			(size 0.3 0.5)
			(layers "F.Cu" "F.Mask" "F.Paste")
			(roundrect_rratio 0.25)
			(net 9 "+3V3")
			(pinfunction "A")
			(pintype "passive")
		)
	)
	(footprint "antmicro-footprints:C_0402_1005Metric"
		(layer "F.Cu")
		(at 96.967962 124.8165 180)
		(descr "Capacitor SMD 0402")
		(tags "capacitor SMD 0402")
		(property "Reference" "C904"
			(at 2.717962 -1.6835 180)
			(layer "F.SilkS")
			(effects
				(font
					(size 0.7 0.7)
					(thickness 0.15)
					(bold yes)
				)
				(justify right bottom)
			)
		)
		(property "Value" "C_100n_0402"
			(at -1.022927 2.155213 0)
			(layer "F.Fab")
			(effects
				(font
					(size 0.7 0.7)
					(thickness 0.15)
				)
				(justify right bottom)
			)
		)
		(property "Datasheet" "https://www.murata.com/products/productdetail?partno=GRM155R61H104KE14%23"
			(at 0 0 180)
			(layer "F.Fab")
			(hide yes)
			(effects
				(font
					(size 1.27 1.27)
					(thickness 0.15)
				)
			)
		)
		(property "Manufacturer" "Murata"
			(at 0 0 180)
			(unlocked yes)
			(layer "F.Fab")
			(hide yes)
			(effects
				(font
					(size 1 1)
					(thickness 0.15)
				)
			)
		)
		(property "MPN" "GRM155R61H104KE14D"
			(at 0 0 180)
			(unlocked yes)
			(layer "F.Fab")
			(hide yes)
			(effects
				(font
					(size 1 1)
					(thickness 0.15)
				)
			)
		)
		(property "Val" "100n"
			(at 0 0 180)
			(unlocked yes)
			(layer "F.Fab")
			(hide yes)
			(effects
				(font
					(size 1 1)
					(thickness 0.15)
				)
			)
		)
		(property "License" "Apache-2.0"
			(at 0 0 180)
			(unlocked yes)
			(layer "F.Fab")
			(hide yes)
			(effects
				(font
					(size 1 1)
					(thickness 0.15)
				)
			)
		)
		(property "Author" "Antmicro"
			(at 0 0 180)
			(unlocked yes)
			(layer "F.Fab")
			(hide yes)
			(effects
				(font
					(size 1 1)
					(thickness 0.15)
				)
			)
		)
		(property "Voltage" "50V"
			(at 0 0 180)
			(unlocked yes)
			(layer "F.Fab")
			(hide yes)
			(effects
				(font
					(size 1 1)
					(thickness 0.15)
				)
			)
		)
		(property "Dielectric" "X5R"
			(at 0 0 180)
			(unlocked yes)
			(layer "F.Fab")
			(hide yes)
			(effects
				(font
					(size 1 1)
					(thickness 0.15)
				)
			)
		)
		(sheetname "/USB/")
		(sheetfile "usb.kicad_sch")
		(attr smd)
		(fp_rect
			(start -0.925 -0.47)
			(end 0.925 0.47)
			(stroke
				(width 0.05)
				(type default)
			)
			(fill no)
			(layer "F.CrtYd")
		)
		(fp_line
			(start 0.504 0.248)
			(end -0.494 0.248)
			(stroke
				(width 0.15)
				(type solid)
			)
			(layer "F.Fab")
		)
		(fp_line
			(start 0.504 -0.25)
			(end 0.504 0.248)
			(stroke
				(width 0.15)
				(type solid)
			)
			(layer "F.Fab")
		)
		(fp_line
			(start -0.494 0.248)
			(end -0.494 -0.25)
			(stroke
				(width 0.15)
				(type solid)
			)
			(layer "F.Fab")
		)
		(fp_line
			(start -0.494 -0.25)
			(end 0.504 -0.25)
			(stroke
				(width 0.15)
				(type solid)
			)
			(layer "F.Fab")
		)
		(fp_text user "${REFERENCE}"
			(at -0.939 4.599 180)
			(layer "F.Fab")
			(effects
				(font
					(size 0.7 0.7)
					(thickness 0.15)
				)
				(justify left bottom)
			)
		)
		(fp_text user "License: Apache-2.0"
			(at -0.939 5.799 180)
			(layer "F.Fab")
			(effects
				(font
					(size 0.7 0.7)
					(thickness 0.15)
				)
				(justify left bottom)
			)
		)
		(fp_text user "Author: Antmicro"
			(at -0.939 3.399 180)
			(layer "F.Fab")
			(effects
				(font
					(size 0.7 0.7)
					(thickness 0.15)
				)
				(justify left bottom)
			)
		)
		(pad "1" smd roundrect
			(at -0.48 0 180)
			(size 0.59 0.64)
			(layers "F.Cu" "F.Mask" "F.Paste")
			(roundrect_rratio 0.25)
			(net 28 "/USB/+5V_{CAP}")
			(pintype "passive")
		)
		(pad "2" smd roundrect
			(at 0.48 0 180)
			(size 0.59 0.64)
			(layers "F.Cu" "F.Mask" "F.Paste")
			(roundrect_rratio 0.25)
			(net 3 "GND")
			(pintype "passive")
		)
	)
	(footprint "antmicro-footprints:TP_SMD_0.75mm"
		(layer "F.Cu")
		(at 97.697962 120.5)
		(property "Reference" "TP910"
			(at 25.935 26.15 0)
			(layer "F.SilkS")
			(effects
				(font
					(size 0.7 0.7)
					(thickness 0.15)
				)
				(justify left bottom)
			)
		)
		(property "Value" "TP_0.75mm_SMD"
			(at 0 1.2 0)
			(layer "F.Fab")
			(effects
				(font
					(size 0.7 0.7)
					(thickness 0.15)
				)
				(justify left bottom)
			)
		)
		(property "MPN" ""
			(at 0 0 0)
			(unlocked yes)
			(layer "F.Fab")
			(hide yes)
			(effects
				(font
					(size 1 1)
					(thickness 0.15)
				)
			)
		)
		(property "Manufacturer" ""
			(at 0 0 0)
			(unlocked yes)
			(layer "F.Fab")
			(hide yes)
			(effects
				(font
					(size 1 1)
					(thickness 0.15)
				)
			)
		)
		(property "Author" "Antmicro"
			(at 0 0 0)
			(unlocked yes)
			(layer "F.Fab")
			(hide yes)
			(effects
				(font
					(size 1 1)
					(thickness 0.15)
				)
			)
		)
		(property "License" "Apache-2.0"
			(at 0 0 0)
			(unlocked yes)
			(layer "F.Fab")
			(hide yes)
			(effects
				(font
					(size 1 1)
					(thickness 0.15)
				)
			)
		)
		(sheetname "/USB/")
		(sheetfile "usb.kicad_sch")
		(attr exclude_from_pos_files exclude_from_bom)
		(fp_circle
			(center 0 0)
			(end 0.475 0)
			(stroke
				(width 0.05)
				(type default)
			)
			(fill no)
			(layer "F.CrtYd")
		)
		(fp_text user "Author: Antmicro"
			(at -0.4 3.901 0)
			(layer "F.Fab")
			(effects
				(font
					(size 0.7 0.7)
					(thickness 0.15)
				)
				(justify left bottom)
			)
		)
		(fp_text user "License: Apache-2.0"
			(at -0.4 5.101 0)
			(layer "F.Fab")
			(effects
				(font
					(size 0.7 0.7)
					(thickness 0.15)
				)
				(justify left bottom)
			)
		)
		(fp_text user "${REFERENCE}"
			(at -0.4 2.7 0)
			(layer "F.Fab")
			(effects
				(font
					(size 0.7 0.7)
					(thickness 0.15)
				)
				(justify left bottom)
			)
		)
		(pad "1" smd circle
			(at 0 0)
			(size 0.75 0.75)
			(layers "F.Cu" "F.Mask")
			(net 435 "Net-(U906-~{VCONN_FAULT})")
			(pinfunction "1")
			(pintype "passive")
		)
	)
)
